(kicad_pcb
	(version 20221018)
	(generator pcbnew)
	(general
    (thickness 1.518)
  )
	(paper "A4")
	(title_block
    (title "Kria K26 Devboard")
    (date "2024-03-26")
    (rev "1.2.5")
    (comment 1 "www.antmicro.com")
    (comment 2 "Antmicro Ltd.")
		(comment 9 "footprints 243-250 of 660")
	)
	(layers
    (0 "F.Cu" mixed)
    (1 "In1.Cu" power)
    (2 "In2.Cu" mixed)
    (3 "In3.Cu" power)
    (4 "In4.Cu" mixed)
    (5 "In5.Cu" power)
    (6 "In6.Cu" mixed)
    (31 "B.Cu" power)
    (32 "B.Adhes" user "B.Adhesive")
    (33 "F.Adhes" user "F.Adhesive")
    (34 "B.Paste" user)
    (35 "F.Paste" user)
    (36 "B.SilkS" user "B.Silkscreen")
    (37 "F.SilkS" user "F.Silkscreen")
    (38 "B.Mask" user)
    (39 "F.Mask" user)
    (40 "Dwgs.User" user "User.Drawings")
    (41 "Cmts.User" user "User.Comments")
    (42 "Eco1.User" user "User.Eco1")
    (43 "Eco2.User" user "User.Eco2")
    (44 "Edge.Cuts" user)
    (45 "Margin" user)
    (46 "B.CrtYd" user "B.Courtyard")
    (47 "F.CrtYd" user "F.Courtyard")
    (48 "B.Fab" user)
    (49 "F.Fab" user)
  )
	(footprint "kria-k26-devboard-footprints:C_0603_1608Metric" (layer "F.Cu")
    (at 167.185 117.455 -90)
    (descr "Capacitor SMD 0603")
    (tags "capacitor 0603")
    (property "Author" "Antmicro")
    (property "Dielectric" "")
    (property "License" "Apache-2.0")
    (property "MPN" "GRM188R60J226MEA0D")
    (property "Manufacturer" "Murata")
    (property "Sheetfile" "dc-dc-conventers.kicad_sch")
    (property "Sheetname" "DC/DC conventers")
    (property "Val" "22u")
    (property "Voltage" "")
    (property "ki_description" " ")
    (attr smd)
    (fp_text reference "C218" (at 2.75 1.93 -90) (layer "F.SilkS")
        (effects (font (size 0.7 0.7) (thickness 0.15)) (justify left bottom))
    )
    (fp_text value "C_22u_0603" (at 0 1.6 -90) (layer "F.Fab") hide
        (effects (font (size 0.7 0.7) (thickness 0.15)) (justify left bottom))
    )
    (fp_text user "Author: Antmicro" (at -1.682 4.894 -90) (layer "F.Fab") hide
        (effects (font (size 0.7 0.7) (thickness 0.15)) (justify left bottom))
    )
    (fp_text user "${REFERENCE}" (at -1.682 3.895 -90) (layer "F.Fab") hide
        (effects (font (size 0.7 0.7) (thickness 0.15)) (justify left bottom))
    )
    (fp_text user "License: Apache-2.0" (at -1.682 5.895 -90) (layer "F.Fab") hide
        (effects (font (size 0.7 0.7) (thickness 0.15)) (justify left bottom))
    )
    (fp_line (start -0.3 -0.3) (end 0.3 -0.3)
      (stroke (width 0.15) (type solid)) (layer "F.SilkS"))
    (fp_line (start -0.3 0.3) (end 0.3 0.3)
      (stroke (width 0.15) (type solid)) (layer "F.SilkS"))
    (fp_rect (start -1.24 -0.7) (end 1.24 0.7)
      (stroke (width 0.05) (type solid)) (fill none) (layer "F.CrtYd"))
    (fp_rect (start -0.8 -0.4) (end 0.8 0.4)
      (stroke (width 0.15) (type solid)) (fill none) (layer "F.Fab"))
    (pad "1" smd roundrect (at -0.7 0 270) (size 0.6 0.8) (layers "F.Cu" "F.Paste" "F.Mask") (roundrect_rratio 0.2)
      (net 768 "/Power Supply/DC/DC conventers/PS_1V2_OUT") (pintype "passive"))
    (pad "2" smd roundrect (at 0.7 0 270) (size 0.6 0.8) (layers "F.Cu" "F.Paste" "F.Mask") (roundrect_rratio 0.2)
      (net 1 "GND") (pintype "passive"))
  )
	(footprint "kria-k26-devboard-footprints:C_0603_1608Metric" (layer "F.Cu")
    (at 165.77 117.45 -90)
    (descr "Capacitor SMD 0603")
    (tags "capacitor 0603")
    (property "Author" "Antmicro")
    (property "Dielectric" "")
    (property "License" "Apache-2.0")
    (property "MPN" "GRM188R60J226MEA0D")
    (property "Manufacturer" "Murata")
    (property "Sheetfile" "dc-dc-conventers.kicad_sch")
    (property "Sheetname" "DC/DC conventers")
    (property "Val" "22u")
    (property "Voltage" "")
    (property "ki_description" " ")
    (attr smd)
    (fp_text reference "C214" (at 2.79 1.42 -90) (layer "F.SilkS")
        (effects (font (size 0.7 0.7) (thickness 0.15)) (justify left bottom))
    )
    (fp_text value "C_22u_0603" (at 0 1.6 -90) (layer "F.Fab") hide
        (effects (font (size 0.7 0.7) (thickness 0.15)) (justify left bottom))
    )
    (fp_text user "${REFERENCE}" (at -1.682 3.895 -90) (layer "F.Fab") hide
        (effects (font (size 0.7 0.7) (thickness 0.15)) (justify left bottom))
    )
    (fp_text user "License: Apache-2.0" (at -1.682 5.895 -90) (layer "F.Fab") hide
        (effects (font (size 0.7 0.7) (thickness 0.15)) (justify left bottom))
    )
    (fp_text user "Author: Antmicro" (at -1.682 4.894 -90) (layer "F.Fab") hide
        (effects (font (size 0.7 0.7) (thickness 0.15)) (justify left bottom))
    )
    (fp_line (start -0.3 -0.3) (end 0.3 -0.3)
      (stroke (width 0.15) (type solid)) (layer "F.SilkS"))
    (fp_line (start -0.3 0.3) (end 0.3 0.3)
      (stroke (width 0.15) (type solid)) (layer "F.SilkS"))
    (fp_rect (start -1.24 -0.7) (end 1.24 0.7)
      (stroke (width 0.05) (type solid)) (fill none) (layer "F.CrtYd"))
    (fp_rect (start -0.8 -0.4) (end 0.8 0.4)
      (stroke (width 0.15) (type solid)) (fill none) (layer "F.Fab"))
    (pad "1" smd roundrect (at -0.7 0 270) (size 0.6 0.8) (layers "F.Cu" "F.Paste" "F.Mask") (roundrect_rratio 0.2)
      (net 768 "/Power Supply/DC/DC conventers/PS_1V2_OUT") (pintype "passive"))
    (pad "2" smd roundrect (at 0.7 0 270) (size 0.6 0.8) (layers "F.Cu" "F.Paste" "F.Mask") (roundrect_rratio 0.2)
      (net 1 "GND") (pintype "passive"))
  )
	(footprint "kria-k26-devboard-footprints:C_0603_1608Metric" (layer "F.Cu")
    (at 167.25 120.3 90)
    (descr "Capacitor SMD 0603")
    (tags "capacitor 0603")
    (property "Author" "Antmicro")
    (property "Dielectric" "")
    (property "License" "Apache-2.0")
    (property "MPN" "C1608X5R1E106M080AC")
    (property "Manufacturer" "TDK")
    (property "Sheetfile" "dc-dc-conventers.kicad_sch")
    (property "Sheetname" "DC/DC conventers")
    (property "Val" "10u/25V")
    (property "Voltage" "")
    (property "ki_description" " ")
    (attr smd)
    (fp_text reference "C204" (at -1.47 -0.81 90) (layer "F.SilkS")
        (effects (font (size 0.7 0.7) (thickness 0.15)) (justify left bottom))
    )
    (fp_text value "C_10u_25V_0603" (at 0 1.6 90) (layer "F.Fab") hide
        (effects (font (size 0.7 0.7) (thickness 0.15)) (justify left bottom))
    )
    (fp_text user "Author: Antmicro" (at -1.682 4.894 90) (layer "F.Fab") hide
        (effects (font (size 0.7 0.7) (thickness 0.15)) (justify left bottom))
    )
    (fp_text user "License: Apache-2.0" (at -1.682 5.895 90) (layer "F.Fab") hide
        (effects (font (size 0.7 0.7) (thickness 0.15)) (justify left bottom))
    )
    (fp_text user "${REFERENCE}" (at -1.682 3.895 90) (layer "F.Fab") hide
        (effects (font (size 0.7 0.7) (thickness 0.15)) (justify left bottom))
    )
    (fp_line (start -0.3 -0.3) (end 0.3 -0.3)
      (stroke (width 0.15) (type solid)) (layer "F.SilkS"))
    (fp_line (start -0.3 0.3) (end 0.3 0.3)
      (stroke (width 0.15) (type solid)) (layer "F.SilkS"))
    (fp_rect (start -1.24 -0.7) (end 1.24 0.7)
      (stroke (width 0.05) (type solid)) (fill none) (layer "F.CrtYd"))
    (fp_rect (start -0.8 -0.4) (end 0.8 0.4)
      (stroke (width 0.15) (type solid)) (fill none) (layer "F.Fab"))
    (pad "1" smd roundrect (at -0.7 0 90) (size 0.6 0.8) (layers "F.Cu" "F.Paste" "F.Mask") (roundrect_rratio 0.2)
      (net 14 "/Power Supply/DC/DC conventers/DC_MAIN_BUS") (pintype "passive"))
    (pad "2" smd roundrect (at 0.7 0 90) (size 0.6 0.8) (layers "F.Cu" "F.Paste" "F.Mask") (roundrect_rratio 0.2)
      (net 1 "GND") (pintype "passive"))
  )
	(footprint "kria-k26-devboard-footprints:TSOT23-6" (layer "F.Cu")
    (at 170.1 120.15 -90)
    (property "Author" "Antmicro")
    (property "License" "Apache-2.0")
    (property "MPN" "AP62301WU-7")
    (property "Manufacturer" "Diodes Incorporated")
    (property "Sheetfile" "dc-dc-conventers.kicad_sch")
    (property "Sheetname" "DC/DC conventers")
    (property "ki_description" "DC-DC Switching Synchronous Buck Regulator, Adjustable, 4.2V-18Vin, 0.8V-7V/3A out, TSOT-26-6")
    (property "ki_keywords" "SMT, PMIC, IC, VOLTAGE")
    (attr smd)
    (fp_text reference "U52" (at 2.24 2.91 180) (layer "F.SilkS")
        (effects (font (size 0.7 0.7) (thickness 0.15)) (justify left bottom))
    )
    (fp_text value "AP62301_TSOT" (at -0.005 2.6 -90) (layer "F.Fab") hide
        (effects (font (size 0.7 0.7) (thickness 0.15)) (justify left bottom))
    )
    (fp_text user "Author: Antmicro" (at -1.893 7.368 -90) (layer "F.Fab") hide
        (effects (font (size 0.7 0.7) (thickness 0.15)) (justify left bottom))
    )
    (fp_text user "License: Apache-2.0" (at -1.893 4.967 -90) (layer "F.Fab") hide
        (effects (font (size 0.7 0.7) (thickness 0.15)) (justify left bottom))
    )
    (fp_text user "${REFERENCE}" (at -1.893 6.168 -90) (layer "F.Fab") hide
        (effects (font (size 0.7 0.7) (thickness 0.15)) (justify left bottom))
    )
    (fp_line (start -1.4805 0.725) (end -1.4795 -0.725)
      (stroke (width 0.15) (type solid)) (layer "F.SilkS"))
    (fp_line (start -1.4805 0.725) (end -1.3905 0.725)
      (stroke (width 0.15) (type solid)) (layer "F.SilkS"))
    (fp_line (start -1.4795 -0.725) (end -1.3905 -0.725)
      (stroke (width 0.15) (type solid)) (layer "F.SilkS"))
    (fp_line (start 1.479 0.73) (end 1.38 0.73)
      (stroke (width 0.15) (type solid)) (layer "F.SilkS"))
    (fp_line (start 1.48 -0.72) (end 1.38 -0.72)
      (stroke (width 0.15) (type solid)) (layer "F.SilkS"))
    (fp_line (start 1.48 -0.72) (end 1.479 0.73)
      (stroke (width 0.15) (type solid)) (layer "F.SilkS"))
    (fp_circle (center -1.499 1.236) (end -1.45 1.236)
      (stroke (width 0.15) (type solid)) (fill solid) (layer "F.SilkS"))
    (fp_rect (start -1.65 -1.61) (end 1.65 1.61)
      (stroke (width 0.05) (type solid)) (fill none) (layer "F.CrtYd"))
    (fp_line (start -1.527 -0.833) (end 1.523 -0.833)
      (stroke (width 0.15) (type solid)) (layer "F.Fab"))
    (fp_line (start -1.527 0.491) (end -1.527 -0.833)
      (stroke (width 0.15) (type solid)) (layer "F.Fab"))
    (fp_line (start -1.527 0.491) (end -1.102 0.916)
      (stroke (width 0.15) (type solid)) (layer "F.Fab"))
    (fp_line (start -1.102 0.916) (end 1.523 0.916)
      (stroke (width 0.15) (type solid)) (layer "F.Fab"))
    (fp_line (start 1.523 -0.833) (end 1.523 0.916)
      (stroke (width 0.15) (type solid)) (layer "F.Fab"))
    (pad "1" smd rect (at -0.952 1.18 270) (size 0.7 0.8) (layers "F.Cu" "F.Paste" "F.Mask")
      (net 1 "GND") (pinfunction "GND") (pintype "power_in"))
    (pad "2" smd rect (at -0.001 1.18 270) (size 0.7 0.8) (layers "F.Cu" "F.Paste" "F.Mask")
      (net 312 "/Power Supply/DC/DC conventers/SW_PS_1V2") (pinfunction "SW") (pintype "power_out"))
    (pad "3" smd rect (at 0.947 1.18 270) (size 0.7 0.8) (layers "F.Cu" "F.Paste" "F.Mask")
      (net 14 "/Power Supply/DC/DC conventers/DC_MAIN_BUS") (pinfunction "VIN") (pintype "power_in"))
    (pad "4" smd rect (at 0.947 -1.18 270) (size 0.7 0.8) (layers "F.Cu" "F.Paste" "F.Mask")
      (net 691 "Net-(U52-FB)") (pinfunction "FB") (pintype "input"))
    (pad "5" smd rect (at -0.001 -1.18 270) (size 0.7 0.8) (layers "F.Cu" "F.Paste" "F.Mask")
      (net 23 "/Power Supply/VCCOEN_PS_M2C") (pinfunction "EN") (pintype "input"))
    (pad "6" smd rect (at -0.952 -1.18 270) (size 0.7 0.8) (layers "F.Cu" "F.Paste" "F.Mask")
      (net 314 "Net-(U52-BST)") (pinfunction "BST") (pintype "output"))
  )
	(footprint "kria-k26-devboard-footprints:TSOT23-6" (layer "F.Cu")
    (at 179.699999 120.175 -90)
    (property "Author" "Antmicro")
    (property "License" "Apache-2.0")
    (property "MPN" "AP62301WU-7")
    (property "Manufacturer" "Diodes Incorporated")
    (property "Sheetfile" "dc-dc-conventers.kicad_sch")
    (property "Sheetname" "DC/DC conventers")
    (property "ki_description" "DC-DC Switching Synchronous Buck Regulator, Adjustable, 4.2V-18Vin, 0.8V-7V/3A out, TSOT-26-6")
    (property "ki_keywords" "SMT, PMIC, IC, VOLTAGE")
    (attr smd)
    (fp_text reference "U51" (at 3.755 -0.470001 90) (layer "F.SilkS")
        (effects (font (size 0.7 0.7) (thickness 0.15)) (justify left bottom))
    )
    (fp_text value "AP62301_TSOT" (at -0.005 2.6 -90) (layer "F.Fab") hide
        (effects (font (size 0.7 0.7) (thickness 0.15)) (justify left bottom))
    )
    (fp_text user "Author: Antmicro" (at -1.893 7.368 -90) (layer "F.Fab") hide
        (effects (font (size 0.7 0.7) (thickness 0.15)) (justify left bottom))
    )
    (fp_text user "License: Apache-2.0" (at -1.893 4.967 -90) (layer "F.Fab") hide
        (effects (font (size 0.7 0.7) (thickness 0.15)) (justify left bottom))
    )
    (fp_text user "${REFERENCE}" (at -1.893 6.168 -90) (layer "F.Fab") hide
        (effects (font (size 0.7 0.7) (thickness 0.15)) (justify left bottom))
    )
    (fp_line (start -1.4805 0.725) (end -1.4795 -0.725)
      (stroke (width 0.15) (type solid)) (layer "F.SilkS"))
    (fp_line (start -1.4805 0.725) (end -1.3905 0.725)
      (stroke (width 0.15) (type solid)) (layer "F.SilkS"))
    (fp_line (start -1.4795 -0.725) (end -1.3905 -0.725)
      (stroke (width 0.15) (type solid)) (layer "F.SilkS"))
    (fp_line (start 1.479 0.73) (end 1.38 0.73)
      (stroke (width 0.15) (type solid)) (layer "F.SilkS"))
    (fp_line (start 1.48 -0.72) (end 1.38 -0.72)
      (stroke (width 0.15) (type solid)) (layer "F.SilkS"))
    (fp_line (start 1.48 -0.72) (end 1.479 0.73)
      (stroke (width 0.15) (type solid)) (layer "F.SilkS"))
    (fp_circle (center -1.499 1.236) (end -1.45 1.236)
      (stroke (width 0.15) (type solid)) (fill solid) (layer "F.SilkS"))
    (fp_rect (start -1.65 -1.61) (end 1.65 1.61)
      (stroke (width 0.05) (type solid)) (fill none) (layer "F.CrtYd"))
    (fp_line (start -1.527 -0.833) (end 1.523 -0.833)
      (stroke (width 0.15) (type solid)) (layer "F.Fab"))
    (fp_line (start -1.527 0.491) (end -1.527 -0.833)
      (stroke (width 0.15) (type solid)) (layer "F.Fab"))
    (fp_line (start -1.527 0.491) (end -1.102 0.916)
      (stroke (width 0.15) (type solid)) (layer "F.Fab"))
    (fp_line (start -1.102 0.916) (end 1.523 0.916)
      (stroke (width 0.15) (type solid)) (layer "F.Fab"))
    (fp_line (start 1.523 -0.833) (end 1.523 0.916)
      (stroke (width 0.15) (type solid)) (layer "F.Fab"))
    (pad "1" smd rect (at -0.952 1.18 270) (size 0.7 0.8) (layers "F.Cu" "F.Paste" "F.Mask")
      (net 1 "GND") (pinfunction "GND") (pintype "power_in"))
    (pad "2" smd rect (at -0.001 1.18 270) (size 0.7 0.8) (layers "F.Cu" "F.Paste" "F.Mask")
      (net 311 "/Power Supply/DC/DC conventers/SW_PS_1V8") (pinfunction "SW") (pintype "power_out"))
    (pad "3" smd rect (at 0.947 1.18 270) (size 0.7 0.8) (layers "F.Cu" "F.Paste" "F.Mask")
      (net 14 "/Power Supply/DC/DC conventers/DC_MAIN_BUS") (pinfunction "VIN") (pintype "power_in"))
    (pad "4" smd rect (at 0.947 -1.18 270) (size 0.7 0.8) (layers "F.Cu" "F.Paste" "F.Mask")
      (net 690 "Net-(U51-FB)") (pinfunction "FB") (pintype "input"))
    (pad "5" smd rect (at -0.001 -1.18 270) (size 0.7 0.8) (layers "F.Cu" "F.Paste" "F.Mask")
      (net 23 "/Power Supply/VCCOEN_PS_M2C") (pinfunction "EN") (pintype "input"))
    (pad "6" smd rect (at -0.952 -1.18 270) (size 0.7 0.8) (layers "F.Cu" "F.Paste" "F.Mask")
      (net 276 "Net-(U51-BST)") (pinfunction "BST") (pintype "output"))
  )
	(footprint "kria-k26-devboard-footprints:R_0402_1005Metric" (layer "F.Cu")
    (at 178.5 115.875)
    (descr "Resistor SMD 0402")
    (tags "resistor SMD 0402")
    (property "Author" "Antmicro")
    (property "License" "Apache-2.0")
    (property "MPN" "CR0402-FX-1001GLF")
    (property "Manufacturer" "Bourns")
    (property "Sheetfile" "dc-dc-conventers.kicad_sch")
    (property "Sheetname" "DC/DC conventers")
    (property "Tolerance" "1%")
    (property "Val" "1k")
    (property "ki_description" "1k resistor in 0402 package with 1% tolerance")
    (attr smd)
    (fp_text reference "R129" (at 3.67 -0.575) (layer "F.SilkS")
        (effects (font (size 0.7 0.7) (thickness 0.15)) (justify left bottom))
    )
    (fp_text value "R_1k_0402" (at 0 1.4) (layer "F.Fab") hide
        (effects (font (size 0.7 0.7) (thickness 0.15)) (justify left bottom))
    )
    (fp_text user "${REFERENCE}" (at -0.95 3.168) (layer "F.Fab") hide
        (effects (font (size 0.7 0.7) (thickness 0.15)) (justify left bottom))
    )
    (fp_text user "License: Apache-2.0" (at -0.95 5.169) (layer "F.Fab") hide
        (effects (font (size 0.7 0.7) (thickness 0.15)) (justify left bottom))
    )
    (fp_text user "Author: Antmicro" (at -0.95 4.169) (layer "F.Fab") hide
        (effects (font (size 0.7 0.7) (thickness 0.15)) (justify left bottom))
    )
    (fp_rect (start -0.93 -0.47) (end 0.93 0.47)
      (stroke (width 0.05) (type solid)) (fill none) (layer "F.CrtYd"))
    (fp_rect (start -0.5 -0.25) (end 0.5 0.25)
      (stroke (width 0.15) (type solid)) (fill none) (layer "F.Fab"))
    (pad "1" smd roundrect (at -0.485 0) (size 0.59 0.64) (layers "F.Cu" "F.Paste" "F.Mask") (roundrect_rratio 0.25)
      (net 765 "/Power Supply/DC/DC conventers/PS_3V3_OUT") (pintype "passive"))
    (pad "2" smd roundrect (at 0.485 0) (size 0.59 0.64) (layers "F.Cu" "F.Paste" "F.Mask") (roundrect_rratio 0.25)
      (net 241 "Net-(D16-Pad1)") (pintype "passive"))
  )
	(footprint "kria-k26-devboard-footprints:R_0402_1005Metric" (layer "F.Cu")
    (at 181.2 122.55 180)
    (descr "Resistor SMD 0402")
    (tags "resistor SMD 0402")
    (property "Author" "Antmicro")
    (property "License" "Apache-2.0")
    (property "MPN" "CR0402-FX-1002GLF")
    (property "Manufacturer" "Bourns")
    (property "Sheetfile" "dc-dc-conventers.kicad_sch")
    (property "Sheetname" "DC/DC conventers")
    (property "Tolerance" "1%")
    (property "Val" "10k")
    (property "ki_description" "10k resistor in 0402 package with 1% tolerance")
    (attr smd)
    (fp_text reference "R136" (at -0.87 -3.28 270) (layer "F.SilkS")
        (effects (font (size 0.7 0.7) (thickness 0.15)) (justify left bottom))
    )
    (fp_text value "R_10k_0402" (at 0 1.4 180) (layer "F.Fab") hide
        (effects (font (size 0.7 0.7) (thickness 0.15)) (justify left bottom))
    )
    (fp_text user "License: Apache-2.0" (at -0.95 5.169 180) (layer "F.Fab") hide
        (effects (font (size 0.7 0.7) (thickness 0.15)) (justify left bottom))
    )
    (fp_text user "Author: Antmicro" (at -0.95 4.169 180) (layer "F.Fab") hide
        (effects (font (size 0.7 0.7) (thickness 0.15)) (justify left bottom))
    )
    (fp_text user "${REFERENCE}" (at -0.95 3.168 180) (layer "F.Fab") hide
        (effects (font (size 0.7 0.7) (thickness 0.15)) (justify left bottom))
    )
    (fp_rect (start -0.93 -0.47) (end 0.93 0.47)
      (stroke (width 0.05) (type solid)) (fill none) (layer "F.CrtYd"))
    (fp_rect (start -0.5 -0.25) (end 0.5 0.25)
      (stroke (width 0.15) (type solid)) (fill none) (layer "F.Fab"))
    (pad "1" smd roundrect (at -0.485 0 180) (size 0.59 0.64) (layers "F.Cu" "F.Paste" "F.Mask") (roundrect_rratio 0.25)
      (net 690 "Net-(U51-FB)") (pintype "passive"))
    (pad "2" smd roundrect (at 0.485 0 180) (size 0.59 0.64) (layers "F.Cu" "F.Paste" "F.Mask") (roundrect_rratio 0.25)
      (net 1 "GND") (pintype "passive"))
  )
	(footprint "kria-k26-devboard-footprints:R_0402_1005Metric" (layer "F.Cu")
    (at 182.6 121.375 -90)
    (descr "Resistor SMD 0402")
    (tags "resistor SMD 0402")
    (property "Author" "Antmicro")
    (property "License" "Apache-2.0")
    (property "MPN" "CR0402-FX-1242GLF")
    (property "Manufacturer" "Bourns")
    (property "Sheetfile" "dc-dc-conventers.kicad_sch")
    (property "Sheetname" "DC/DC conventers")
    (property "Tolerance" "1%")
    (property "Val" "12k4")
    (property "ki_description" "12k4 resistor in 0402 package with 1% tolerance")
    (attr smd)
    (fp_text reference "R135" (at 3.675 -0.46 -90) (layer "F.SilkS")
        (effects (font (size 0.7 0.7) (thickness 0.15)) (justify left bottom))
    )
    (fp_text value "R_12k4_0402" (at 0 1.4 -90) (layer "F.Fab") hide
        (effects (font (size 0.7 0.7) (thickness 0.15)) (justify left bottom))
    )
    (fp_text user "Author: Antmicro" (at -0.95 4.169 -90) (layer "F.Fab") hide
        (effects (font (size 0.7 0.7) (thickness 0.15)) (justify left bottom))
    )
    (fp_text user "${REFERENCE}" (at -0.95 3.168 -90) (layer "F.Fab") hide
        (effects (font (size 0.7 0.7) (thickness 0.15)) (justify left bottom))
    )
    (fp_text user "License: Apache-2.0" (at -0.95 5.169 -90) (layer "F.Fab") hide
        (effects (font (size 0.7 0.7) (thickness 0.15)) (justify left bottom))
    )
    (fp_rect (start -0.93 -0.47) (end 0.93 0.47)
      (stroke (width 0.05) (type solid)) (fill none) (layer "F.CrtYd"))
    (fp_rect (start -0.5 -0.25) (end 0.5 0.25)
      (stroke (width 0.15) (type solid)) (fill none) (layer "F.Fab"))
    (pad "1" smd roundrect (at -0.485 0 270) (size 0.59 0.64) (layers "F.Cu" "F.Paste" "F.Mask") (roundrect_rratio 0.25)
      (net 767 "/Power Supply/DC/DC conventers/PS_1V8_OUT") (pintype "passive"))
    (pad "2" smd roundrect (at 0.485 0 270) (size 0.59 0.64) (layers "F.Cu" "F.Paste" "F.Mask") (roundrect_rratio 0.25)
      (net 690 "Net-(U51-FB)") (pintype "passive"))
  )
)
